FILE_TYPE = MULTI_PHYS_TABLE;
PART 'NPN'
{===================================================================================================================================================================================================================================}
:VALUE          | PACK_TYPE   | MATERIAL | PART_NUMBER     = EnvComp                  | PART_NUMBER  | JEDEC_TYPE | CLASS | DESCRIPTION                           | HEIGHT       | COMPONENT_TYPE | LEAD_LENGTH | LPID   | SPEED_URL | Status |RPL| AML | Bus_Unit | Days ;
{===================================================================================================================================================================================================================================}
'MMBT3904'      | 'SM'        | 'IC'     | 'C52245-001'(!) = 'YES;YES;CNC;CNC;ok;CIP' | 'C52245-001' | 'SOT23B'   | 'IC'  | 'SWITCHING TRANSISTOR'                | '0.045 IN'   | 'SMALLSMT'     | ''          | '801'  | 'http://speed.intel.com:8081/speed/module/pdm/item/pdm_item_detail_direct.asp?item_cde=C52245-001&item_rev=01&url_param=unused' | 'Approved' | 'YES' | '13' | 'SMO_IC' | '294' 
'MMBT3904'      | 'SM'        | 'EMPTY'  | 'C52245-001'(!) = 'YES;YES;CNC;CNC;ok;CIP' | 'C52245-001' | 'SOT23B'   | 'IO'  | 'SWITCHING TRANSISTOR'                | '0.045 IN'   | 'SMALLSMT'     | ''          | '801'  | 'http://speed.intel.com:8081/speed/module/pdm/item/pdm_item_detail_direct.asp?item_cde=C52245-001&item_rev=01&url_param=unused' | 'Approved' | 'YES' | '13' | 'SMO_IC' | '294' 
END_PART
END.
